(kicad_pcb
	(version 20260206)
	(generator "pcbnew")
	(generator_version "10.0")
	(general
		(thickness 1.6)
		(legacy_teardrops no)
	)
	(paper "A4")
	(title_block
		(title "03242023_DA0F0TMBIJ0_F0T_Motherboard_J_brd_V01_OCP.brd")
		(comment 1 "Grand Teton / footprints 2140-2144 of 6105")
	)
	(layers
		(0 "F.Cu" signal "TOP")
		(4 "In1.Cu" signal "GND")
		(6 "In2.Cu" signal "IN1")
		(8 "In3.Cu" signal "GND1")
		(10 "In4.Cu" signal "IN2")
		(12 "In5.Cu" signal "GND2")
		(14 "In6.Cu" signal "IN3")
		(16 "In7.Cu" signal "GND3")
		(18 "In8.Cu" signal "VCC")
		(20 "In9.Cu" signal "VCC1")
		(22 "In10.Cu" signal "GND4")
		(24 "In11.Cu" signal "IN4")
		(26 "In12.Cu" signal "GND5")
		(28 "In13.Cu" signal "IN5")
		(30 "In14.Cu" signal "GND6")
		(32 "In15.Cu" signal "IN6")
		(34 "In16.Cu" signal "GND7")
		(2 "B.Cu" signal "BOTTOM")
		(9 "F.Adhes" user "F.Adhesive")
		(11 "B.Adhes" user "B.Adhesive")
		(13 "F.Paste" user "Package Geometry/Pastemask Top")
		(15 "B.Paste" user "Package Geometry/Pastemask Bottom")
		(5 "F.SilkS" user "Ref Des/Silkscreen Top")
		(7 "B.SilkS" user "Ref Des/Silkscreen Bottom")
		(1 "F.Mask" user "Board Geometry/Soldermask Top")
		(3 "B.Mask" user "Board Geometry/Soldermask Bottom")
		(17 "Dwgs.User" user "User.Drawings")
		(19 "Cmts.User" user "User.Comments")
		(21 "Eco1.User" user "User.Eco1")
		(23 "Eco2.User" user "User.Eco2")
		(25 "Edge.Cuts" user "Board Geometry/Outline")
		(27 "Margin" user)
		(31 "F.CrtYd" user "Package Geometry/Place Bound Top")
		(29 "B.CrtYd" user "Package Geometry/Place Bound Bottom")
		(35 "F.Fab" user "Ref Des/Assembly Top")
		(33 "B.Fab" user "Ref Des/Assembly Bottom")
	)
	(footprint ""
		(layer "F.Cu")
		(at 432.151536 -101.97719)
		(property "Reference" "R3796"
			(at 0 0 0)
			(layer "F.SilkS")
			(hide yes)
			(effects
				(font
					(size 1.27 1.27)
				)
			)
		)
		(property "Value" ""
			(at 0 0 0)
			(layer "F.Fab")
			(effects
				(font
					(size 1.27 1.27)
				)
			)
		)
		(duplicate_pad_numbers_are_jumpers no)
		(fp_line
			(start -0.7874 -0.4064)
			(end 0.7874 -0.4064)
			(stroke
				(width 0.1524)
				(type default)
			)
			(layer "F.SilkS")
		)
		(fp_line
			(start -0.7874 0.4064)
			(end -0.7874 -0.4064)
			(stroke
				(width 0.1524)
				(type default)
			)
			(layer "F.SilkS")
		)
		(fp_line
			(start 0.7874 -0.4064)
			(end 0.7874 0.4064)
			(stroke
				(width 0.1524)
				(type default)
			)
			(layer "F.SilkS")
		)
		(fp_line
			(start 0.7874 0.4064)
			(end -0.7874 0.4064)
			(stroke
				(width 0.1524)
				(type default)
			)
			(layer "F.SilkS")
		)
		(fp_line
			(start -0.67945 -0.305054)
			(end -0.12065 -0.305054)
			(stroke
				(width 0.1)
				(type default)
			)
			(layer "F.Fab")
		)
		(fp_line
			(start -0.67945 0.3048)
			(end -0.67945 -0.305054)
			(stroke
				(width 0.1)
				(type default)
			)
			(layer "F.Fab")
		)
		(fp_line
			(start -0.12065 -0.305054)
			(end -0.12065 -0.2794)
			(stroke
				(width 0.1)
				(type default)
			)
			(layer "F.Fab")
		)
		(fp_line
			(start -0.12065 -0.2794)
			(end 0.12065 -0.2794)
			(stroke
				(width 0.1)
				(type default)
			)
			(layer "F.Fab")
		)
		(fp_line
			(start -0.12065 0.2794)
			(end -0.12065 0.3048)
			(stroke
				(width 0.1)
				(type default)
			)
			(layer "F.Fab")
		)
		(fp_line
			(start -0.12065 0.3048)
			(end -0.67945 0.3048)
			(stroke
				(width 0.1)
				(type default)
			)
			(layer "F.Fab")
		)
		(fp_line
			(start 0.120396 0.2794)
			(end -0.12065 0.2794)
			(stroke
				(width 0.1)
				(type default)
			)
			(layer "F.Fab")
		)
		(fp_line
			(start 0.120396 0.3048)
			(end 0.120396 0.2794)
			(stroke
				(width 0.1)
				(type default)
			)
			(layer "F.Fab")
		)
		(fp_line
			(start 0.12065 -0.3048)
			(end 0.67945 -0.3048)
			(stroke
				(width 0.1)
				(type default)
			)
			(layer "F.Fab")
		)
		(fp_line
			(start 0.12065 -0.2794)
			(end 0.12065 -0.3048)
			(stroke
				(width 0.1)
				(type default)
			)
			(layer "F.Fab")
		)
		(fp_line
			(start 0.67945 -0.3048)
			(end 0.67945 0.3048)
			(stroke
				(width 0.1)
				(type default)
			)
			(layer "F.Fab")
		)
		(fp_line
			(start 0.67945 0.3048)
			(end 0.120396 0.3048)
			(stroke
				(width 0.1)
				(type default)
			)
			(layer "F.Fab")
		)
		(pad "1" smd circle
			(at -0.40005 0)
			(size 0 0)
			(layers "F.Cu" "F.Mask" "F.Paste")
			(net "P3V3_AUX")
		)
		(pad "2" smd circle
			(at 0.40005 0)
			(size 0 0)
			(layers "F.Cu" "F.Mask" "F.Paste")
			(net "P3V3_OCP_FAULT_1")
		)
	)
	(footprint ""
		(layer "F.Cu")
		(at 469.694514 -41.87825 -90)
		(property "Reference" "R4068"
			(at 0 0 270)
			(layer "F.SilkS")
			(hide yes)
			(effects
				(font
					(size 1.27 1.27)
				)
			)
		)
		(property "Value" ""
			(at 0 0 270)
			(layer "F.Fab")
			(effects
				(font
					(size 1.27 1.27)
				)
			)
		)
		(duplicate_pad_numbers_are_jumpers no)
		(fp_line
			(start -0.7874 0.4064)
			(end -0.7874 -0.4064)
			(stroke
				(width 0.1524)
				(type default)
			)
			(layer "F.SilkS")
		)
		(fp_line
			(start 0.7874 0.4064)
			(end -0.7874 0.4064)
			(stroke
				(width 0.1524)
				(type default)
			)
			(layer "F.SilkS")
		)
		(fp_line
			(start -0.7874 -0.4064)
			(end 0.7874 -0.4064)
			(stroke
				(width 0.1524)
				(type default)
			)
			(layer "F.SilkS")
		)
		(fp_line
			(start 0.7874 -0.4064)
			(end 0.7874 0.4064)
			(stroke
				(width 0.1524)
				(type default)
			)
			(layer "F.SilkS")
		)
		(fp_line
			(start -0.67945 0.3048)
			(end -0.67945 -0.305054)
			(stroke
				(width 0.1)
				(type default)
			)
			(layer "F.Fab")
		)
		(fp_line
			(start -0.12065 0.3048)
			(end -0.67945 0.3048)
			(stroke
				(width 0.1)
				(type default)
			)
			(layer "F.Fab")
		)
		(fp_line
			(start 0.120396 0.3048)
			(end 0.120396 0.2794)
			(stroke
				(width 0.1)
				(type default)
			)
			(layer "F.Fab")
		)
		(fp_line
			(start 0.67945 0.3048)
			(end 0.120396 0.3048)
			(stroke
				(width 0.1)
				(type default)
			)
			(layer "F.Fab")
		)
		(fp_line
			(start -0.12065 0.2794)
			(end -0.12065 0.3048)
			(stroke
				(width 0.1)
				(type default)
			)
			(layer "F.Fab")
		)
		(fp_line
			(start 0.120396 0.2794)
			(end -0.12065 0.2794)
			(stroke
				(width 0.1)
				(type default)
			)
			(layer "F.Fab")
		)
		(fp_line
			(start -0.12065 -0.2794)
			(end 0.12065 -0.2794)
			(stroke
				(width 0.1)
				(type default)
			)
			(layer "F.Fab")
		)
		(fp_line
			(start 0.12065 -0.2794)
			(end 0.12065 -0.3048)
			(stroke
				(width 0.1)
				(type default)
			)
			(layer "F.Fab")
		)
		(fp_line
			(start 0.12065 -0.3048)
			(end 0.67945 -0.3048)
			(stroke
				(width 0.1)
				(type default)
			)
			(layer "F.Fab")
		)
		(fp_line
			(start 0.67945 -0.3048)
			(end 0.67945 0.3048)
			(stroke
				(width 0.1)
				(type default)
			)
			(layer "F.Fab")
		)
		(fp_line
			(start -0.67945 -0.305054)
			(end -0.12065 -0.305054)
			(stroke
				(width 0.1)
				(type default)
			)
			(layer "F.Fab")
		)
		(fp_line
			(start -0.12065 -0.305054)
			(end -0.12065 -0.2794)
			(stroke
				(width 0.1)
				(type default)
			)
			(layer "F.Fab")
		)
		(pad "1" smd circle
			(at -0.40005 0 270)
			(size 0 0)
			(layers "F.Cu" "F.Mask" "F.Paste")
			(net "P12V_AUX")
		)
		(pad "2" smd circle
			(at 0.40005 0 270)
			(size 0 0)
			(layers "F.Cu" "F.Mask" "F.Paste")
			(net "P12V_OCP_1_EN_G")
		)
	)
	(footprint ""
		(layer "F.Cu")
		(at 288.786062 -362.7755)
		(property "Reference" "PU72_P0_4"
			(at -10.910062 -7.494778 0)
			(unlocked yes)
			(layer "F.SilkS")
			(effects
				(font
					(size 0.7874 0.5842)
					(thickness 0.1524)
				)
				(justify left)
			)
		)
		(property "Value" ""
			(at 0 0 0)
			(layer "F.Fab")
			(effects
				(font
					(size 1.27 1.27)
				)
			)
		)
		(duplicate_pad_numbers_are_jumpers no)
		(fp_line
			(start -2.500122 -2.999994)
			(end -2.24409 -2.999994)
			(stroke
				(width 0.1524)
				(type default)
			)
			(layer "F.SilkS")
		)
		(fp_line
			(start -2.500122 -2.529078)
			(end -2.500122 -2.999994)
			(stroke
				(width 0.1524)
				(type default)
			)
			(layer "F.SilkS")
		)
		(fp_line
			(start -2.500122 0.6604)
			(end -2.500122 0.229108)
			(stroke
				(width 0.1524)
				(type default)
			)
			(layer "F.SilkS")
		)
		(fp_line
			(start -2.500122 2.999994)
			(end -2.500122 2.339594)
			(stroke
				(width 0.1524)
				(type default)
			)
			(layer "F.SilkS")
		)
		(fp_line
			(start -2.2987 2.999994)
			(end -2.500122 2.999994)
			(stroke
				(width 0.1524)
				(type default)
			)
			(layer "F.SilkS")
		)
		(fp_line
			(start 2.31394 -2.999994)
			(end 2.500122 -2.999994)
			(stroke
				(width 0.1524)
				(type default)
			)
			(layer "F.SilkS")
		)
		(fp_line
			(start 2.500122 -2.999994)
			(end 2.500122 -2.44348)
			(stroke
				(width 0.1524)
				(type default)
			)
			(layer "F.SilkS")
		)
		(fp_line
			(start 2.500122 2.339594)
			(end 2.500122 2.999994)
			(stroke
				(width 0.1524)
				(type default)
			)
			(layer "F.SilkS")
		)
		(fp_line
			(start 2.500122 2.999994)
			(end 2.2987 2.999994)
			(stroke
				(width 0.1524)
				(type default)
			)
			(layer "F.SilkS")
		)
		(fp_poly
			(pts
				(xy -2.211832 -3.514598) (xy -2.719832 -2.498598) (xy -3.227832 -3.514598)
			)
			(stroke
				(width 0)
				(type default)
			)
			(fill yes)
			(layer "F.SilkS")
		)
		(fp_line
			(start -2.500122 -2.999994)
			(end 2.500122 -2.999994)
			(stroke
				(width 0.1)
				(type default)
			)
			(layer "F.Fab")
		)
		(fp_line
			(start -2.500122 2.999994)
			(end -2.500122 -2.999994)
			(stroke
				(width 0.1)
				(type default)
			)
			(layer "F.Fab")
		)
		(fp_line
			(start 2.500122 -2.999994)
			(end 2.500122 2.999994)
			(stroke
				(width 0.1)
				(type default)
			)
			(layer "F.Fab")
		)
		(fp_line
			(start 2.500122 2.999994)
			(end -2.500122 2.999994)
			(stroke
				(width 0.1)
				(type default)
			)
			(layer "F.Fab")
		)
		(fp_poly
			(pts
				(xy -4.218432 -2.783078) (xy -4.218432 -1.767078) (xy -3.202432 -2.275078)
			)
			(stroke
				(width 0)
				(type default)
			)
			(fill yes)
			(layer "F.Fab")
		)
		(pad "1" smd rect
			(at -2.400046 -2.275078 90)
			(size 0.2286 0.6096)
			(layers "F.Cu" "F.Mask" "F.Paste")
			(net "PVCCFA_EHV_FIVRA_CPU0_VOS4")
		)
		(pad "2" smd rect
			(at -2.400046 -1.82499 90)
			(size 0.2286 0.6096)
			(layers "F.Cu" "F.Mask" "F.Paste")
			(net "GND")
		)
		(pad "3" smd rect
			(at -2.400046 -1.374902 90)
			(size 0.2286 0.6096)
			(layers "F.Cu" "F.Mask" "F.Paste")
			(net "PVCCFA_EHV_FIVRA_CPU0_VDD4")
		)
		(pad "4" smd rect
			(at -2.400046 -0.925068 90)
			(size 0.2286 0.6096)
			(layers "F.Cu" "F.Mask" "F.Paste")
			(net "PVCCFA_EHV_FIVRA_CPU0_PVCC2")
		)
		(pad "5" smd rect
			(at -2.400046 -0.47498 90)
			(size 0.2286 0.6096)
			(layers "F.Cu" "F.Mask" "F.Paste")
			(net "GND")
		)
		(pad "6" smd rect
			(at -2.400046 -0.024892 90)
			(size 0.2286 0.6096)
			(layers "F.Cu" "F.Mask" "F.Paste")
			(net "Net_8508")
		)
		(pad "7_9-20_24" smd circle
			(at 0 1.150112 90)
			(size 0 0)
			(layers "F.Cu" "F.Mask" "F.Paste")
			(net "GND")
		)
		(pad "10_19" smd rect
			(at 0 2.899918 90)
			(size 0.6096 4.318)
			(layers "F.Cu" "F.Mask" "F.Paste")
			(net "SW_PVCCFA_EHV_FIVRA_CPU0_SW4")
		)
		(pad "25_29" smd rect
			(at 1.549908 -1.279906 270)
			(size 2.0574 2.3114)
			(layers "F.Cu" "F.Mask" "F.Paste")
			(net "SW_P12V_PVCCFA_EHV_FIVRA_CPU0_L")
		)
		(pad "30" smd rect
			(at 2.05994 -2.899918)
			(size 0.2286 0.6096)
			(layers "F.Cu" "F.Mask" "F.Paste")
			(net "SW_P12V_PVCCFA_EHV_FIVRA_CPU0_L")
		)
		(pad "31" smd rect
			(at 1.610106 -2.899918)
			(size 0.2286 0.6096)
			(layers "F.Cu" "F.Mask" "F.Paste")
			(net "Net_8509")
		)
		(pad "32" smd rect
			(at 1.160018 -2.899918)
			(size 0.2286 0.6096)
			(layers "F.Cu" "F.Mask" "F.Paste")
			(net "SW_PVCCFA_EHV_FIVRA_CPU0_BOOTR4")
		)
		(pad "33" smd rect
			(at 0.70993 -2.899918)
			(size 0.2286 0.6096)
			(layers "F.Cu" "F.Mask" "F.Paste")
			(net "SW_PVCCFA_EHV_FIVRA_CPU0_BOOT4")
		)
		(pad "34" smd rect
			(at 0.260096 -2.899918)
			(size 0.2286 0.6096)
			(layers "F.Cu" "F.Mask" "F.Paste")
			(net "PVCCFA_EHV_FIVRA_CPU0_PWM4")
		)
		(pad "35" smd rect
			(at -0.189992 -2.899918)
			(size 0.2286 0.6096)
			(layers "F.Cu" "F.Mask" "F.Paste")
			(net "PVCCFA_EHV_FIVRA_CPU0_VDD4")
		)
		(pad "36" smd rect
			(at -0.64008 -2.899918)
			(size 0.2286 0.6096)
			(layers "F.Cu" "F.Mask" "F.Paste")
			(net "PVCCFA_EHV_FIVRA_CPU0_BTSEN")
		)
		(pad "37" smd rect
			(at -1.089914 -2.899918)
			(size 0.2286 0.6096)
			(layers "F.Cu" "F.Mask" "F.Paste")
			(net "PVCCFA_EHV_FIVRA_CPU0_LSET4")
		)
		(pad "38" smd rect
			(at -1.540002 -2.899918)
			(size 0.2286 0.6096)
			(layers "F.Cu" "F.Mask" "F.Paste")
			(net "PVCCFA_EHV_FIVRA_CPU0_IMON4")
		)
		(pad "39" smd rect
			(at -1.99009 -2.899918)
			(size 0.2286 0.6096)
			(layers "F.Cu" "F.Mask" "F.Paste")
			(net "PVCCIN_CPU0_VREF")
		)
		(pad "40" smd rect
			(at -0.87503 -1.27508)
			(size 1.7526 1.9558)
			(layers "F.Cu" "F.Mask" "F.Paste")
			(net "GND")
		)
		(pad "41" smd rect
			(at -1.525016 0.249936 270)
			(size 0.3048 0.4572)
			(layers "F.Cu" "F.Mask" "F.Paste")
			(net "Net_8507")
		)
		(zone
			(layer "F.Cu")
			(hatch none 0.5)
			(connect_pads
				(clearance 0)
			)
			(min_thickness 0.25)
			(keepout
				(tracks not_allowed)
				(vias allowed)
				(pads allowed)
				(copperpour not_allowed)
				(footprints allowed)
			)
			(placement
				(enabled no)
				(sheetname "")
			)
			(fill
				(thermal_gap 0.5)
				(thermal_bridge_width 0.5)
				(island_removal_mode 0)
			)
			(polygon
				(pts
					(xy 286.28594 -359.775506) (xy 286.28594 -360.500168) (xy 291.286184 -360.500168) (xy 291.286184 -359.775506)
					(xy 290.995862 -359.775506) (xy 290.995862 -360.231182) (xy 286.576262 -360.231182) (xy 286.576262 -359.775506)
				)
			)
		)
		(zone
			(layer "F.Cu")
			(hatch none 0.5)
			(connect_pads
				(clearance 0)
			)
			(min_thickness 0.25)
			(keepout
				(tracks not_allowed)
				(vias allowed)
				(pads allowed)
				(copperpour not_allowed)
				(footprints allowed)
			)
			(placement
				(enabled no)
				(sheetname "")
			)
			(fill
				(thermal_gap 0.5)
				(thermal_bridge_width 0.5)
				(island_removal_mode 0)
			)
			(polygon
				(pts
					(xy 287.0073 -363.02188) (xy 287.78708 -363.02188) (xy 287.78708 -362.712508) (xy 287.83534 -362.712508)
					(xy 287.83534 -362.08716) (xy 287.77438 -362.0262) (xy 286.28594 -362.0262) (xy 286.28594 -362.482892)
					(xy 286.981646 -362.482892) (xy 286.981646 -362.322364) (xy 287.540446 -362.322364) (xy 287.540446 -362.728764)
					(xy 286.981646 -362.728764) (xy 286.981646 -362.508292) (xy 286.28594 -362.508292) (xy 286.28594 -362.635292)
					(xy 286.741616 -362.635292) (xy 286.741616 -363.007148) (xy 287.0073 -363.007148)
				)
			)
		)
	)
	(footprint ""
		(layer "F.Cu")
		(at 441.99048 -51.077368 -90)
		(property "Reference" "C1338"
			(at 0 0 270)
			(layer "F.SilkS")
			(hide yes)
			(effects
				(font
					(size 1.27 1.27)
				)
			)
		)
		(property "Value" ""
			(at 0 0 270)
			(layer "F.Fab")
			(effects
				(font
					(size 1.27 1.27)
				)
			)
		)
		(duplicate_pad_numbers_are_jumpers no)
		(fp_line
			(start -1.524 0.762)
			(end -1.524 -0.762)
			(stroke
				(width 0.1524)
				(type default)
			)
			(layer "F.SilkS")
		)
		(fp_line
			(start 1.524 0.762)
			(end -1.524 0.762)
			(stroke
				(width 0.1524)
				(type default)
			)
			(layer "F.SilkS")
		)
		(fp_line
			(start -1.524 -0.762)
			(end 1.524 -0.762)
			(stroke
				(width 0.1524)
				(type default)
			)
			(layer "F.SilkS")
		)
		(fp_line
			(start 1.524 -0.762)
			(end 1.524 0.762)
			(stroke
				(width 0.1524)
				(type default)
			)
			(layer "F.SilkS")
		)
		(fp_line
			(start -1.1049 0.724916)
			(end 1.1049 0.724916)
			(stroke
				(width 0.1)
				(type default)
			)
			(layer "F.Fab")
		)
		(fp_line
			(start 1.1049 0.724916)
			(end 1.1049 -0.724916)
			(stroke
				(width 0.1)
				(type default)
			)
			(layer "F.Fab")
		)
		(fp_line
			(start -1.1049 -0.724916)
			(end -1.1049 0.724916)
			(stroke
				(width 0.1)
				(type default)
			)
			(layer "F.Fab")
		)
		(fp_line
			(start 1.1049 -0.724916)
			(end -1.1049 -0.724916)
			(stroke
				(width 0.1)
				(type default)
			)
			(layer "F.Fab")
		)
		(pad "1" smd rect
			(at -0.889 0 90)
			(size 1.016 1.27)
			(layers "F.Cu" "F.Mask" "F.Paste")
			(net "P3V3_AUX")
		)
		(pad "2" smd rect
			(at 0.889 0 90)
			(size 1.016 1.27)
			(layers "F.Cu" "F.Mask" "F.Paste")
			(net "GND")
		)
	)
	(footprint ""
		(layer "F.Cu")
		(at 320.190622 -62.880748)
		(property "Reference" "R615"
			(at 0 0 0)
			(layer "F.SilkS")
			(hide yes)
			(effects
				(font
					(size 1.27 1.27)
				)
			)
		)
		(property "Value" ""
			(at 0 0 0)
			(layer "F.Fab")
			(effects
				(font
					(size 1.27 1.27)
				)
			)
		)
		(duplicate_pad_numbers_are_jumpers no)
		(fp_line
			(start -0.7874 -0.4064)
			(end 0.7874 -0.4064)
			(stroke
				(width 0.1524)
				(type default)
			)
			(layer "F.SilkS")
		)
		(fp_line
			(start -0.7874 0.4064)
			(end -0.7874 -0.4064)
			(stroke
				(width 0.1524)
				(type default)
			)
			(layer "F.SilkS")
		)
		(fp_line
			(start 0.7874 -0.4064)
			(end 0.7874 0.4064)
			(stroke
				(width 0.1524)
				(type default)
			)
			(layer "F.SilkS")
		)
		(fp_line
			(start 0.7874 0.4064)
			(end -0.7874 0.4064)
			(stroke
				(width 0.1524)
				(type default)
			)
			(layer "F.SilkS")
		)
		(fp_line
			(start -0.67945 -0.305054)
			(end -0.12065 -0.305054)
			(stroke
				(width 0.1)
				(type default)
			)
			(layer "F.Fab")
		)
		(fp_line
			(start -0.67945 0.3048)
			(end -0.67945 -0.305054)
			(stroke
				(width 0.1)
				(type default)
			)
			(layer "F.Fab")
		)
		(fp_line
			(start -0.12065 -0.305054)
			(end -0.12065 -0.2794)
			(stroke
				(width 0.1)
				(type default)
			)
			(layer "F.Fab")
		)
		(fp_line
			(start -0.12065 -0.2794)
			(end 0.12065 -0.2794)
			(stroke
				(width 0.1)
				(type default)
			)
			(layer "F.Fab")
		)
		(fp_line
			(start -0.12065 0.2794)
			(end -0.12065 0.3048)
			(stroke
				(width 0.1)
				(type default)
			)
			(layer "F.Fab")
		)
		(fp_line
			(start -0.12065 0.3048)
			(end -0.67945 0.3048)
			(stroke
				(width 0.1)
				(type default)
			)
			(layer "F.Fab")
		)
		(fp_line
			(start 0.120396 0.2794)
			(end -0.12065 0.2794)
			(stroke
				(width 0.1)
				(type default)
			)
			(layer "F.Fab")
		)
		(fp_line
			(start 0.120396 0.3048)
			(end 0.120396 0.2794)
			(stroke
				(width 0.1)
				(type default)
			)
			(layer "F.Fab")
		)
		(fp_line
			(start 0.12065 -0.3048)
			(end 0.67945 -0.3048)
			(stroke
				(width 0.1)
				(type default)
			)
			(layer "F.Fab")
		)
		(fp_line
			(start 0.12065 -0.2794)
			(end 0.12065 -0.3048)
			(stroke
				(width 0.1)
				(type default)
			)
			(layer "F.Fab")
		)
		(fp_line
			(start 0.67945 -0.3048)
			(end 0.67945 0.3048)
			(stroke
				(width 0.1)
				(type default)
			)
			(layer "F.Fab")
		)
		(fp_line
			(start 0.67945 0.3048)
			(end 0.120396 0.3048)
			(stroke
				(width 0.1)
				(type default)
			)
			(layer "F.Fab")
		)
		(pad "1" smd circle
			(at -0.40005 0)
			(size 0 0)
			(layers "F.Cu" "F.Mask" "F.Paste")
			(net "P3V3_AUX")
		)
		(pad "2" smd circle
			(at 0.40005 0)
			(size 0 0)
			(layers "F.Cu" "F.Mask" "F.Paste")
			(net "FM_PCH_VISA_DEFAULT")
		)
	)
)
